FILE_TYPE=LIBRARY_PARTS;
primitive 'MTG_KEYHOLE','MTG_KEYHOLE_TH';
  pin
    '1':
      PIN_NUMBER='(1)';
      PINUSE='UNSPEC';
      NO_LOAD_CHECK='BOTH';
      NO_IO_CHECK='BOTH';
      ALLOW_CONNECT='TRUE';
  end_pin;
  body
    PART_NAME='MTG_KEYHOLE';
    PHYS_DES_PREFIX='TH';
  end_body;
end_primitive;
END.
